# T6G (Grand Teton) — schematic netlist excerpt (pin names and nets, part order shuffled) for the footprints in the layout excerpt that follows; sources: Cadence DE-HDL packaged netlist, KiCad conversion of 04192023_DAF0TMB3IC0_F0TG_MB_C_brd_V02_OCP.brd

PC82_C1P0_2  Q_CAP  2.2UF 10V 10% X6S  pkg C0402  page 201 : A = PVDDCR_CPU1_P0_PVCC ; B = GND

(kicad_pcb
	(version 20260206)
	(generator "pcbnew")
	(generator_version "10.0")
	(general
		(thickness 1.6)
		(legacy_teardrops no)
	)
	(paper "A4")
	(title_block
		(title "04192023_DAF0TMB3IC0_F0TG_MB_C_brd_V02_OCP.brd")
		(comment 1 "Grand Teton / footprints 2888-2888 of 8354")
	)
	(layers
		(0 "F.Cu" signal "TOP")
		(4 "In1.Cu" signal "GND")
		(6 "In2.Cu" signal "IN1")
		(8 "In3.Cu" signal "GND1")
		(10 "In4.Cu" signal "IN2")
		(12 "In5.Cu" signal "GND2")
		(14 "In6.Cu" signal "IN3")
		(16 "In7.Cu" signal "GND3")
		(18 "In8.Cu" signal "VCC")
		(20 "In9.Cu" signal "VCC1")
		(22 "In10.Cu" signal "GND4")
		(24 "In11.Cu" signal "IN4")
		(26 "In12.Cu" signal "GND5")
		(28 "In13.Cu" signal "IN5")
		(30 "In14.Cu" signal "GND6")
		(32 "In15.Cu" signal "IN6")
		(34 "In16.Cu" signal "GND7")
		(2 "B.Cu" signal "BOTTOM")
		(9 "F.Adhes" user "F.Adhesive")
		(11 "B.Adhes" user "B.Adhesive")
		(13 "F.Paste" user "Package Geometry/Pastemask Top")
		(15 "B.Paste" user "Package Geometry/Pastemask Bottom")
		(5 "F.SilkS" user "Ref Des/Silkscreen Top")
		(7 "B.SilkS" user "Ref Des/Silkscreen Bottom")
		(1 "F.Mask" user "Board Geometry/Soldermask Top")
		(3 "B.Mask" user "Board Geometry/Soldermask Bottom")
		(17 "Dwgs.User" user "User.Drawings")
		(19 "Cmts.User" user "User.Comments")
		(21 "Eco1.User" user "User.Eco1")
		(23 "Eco2.User" user "User.Eco2")
		(25 "Edge.Cuts" user "Board Geometry/Outline")
		(27 "Margin" user)
		(31 "F.CrtYd" user "Package Geometry/Place Bound Top")
		(29 "B.CrtYd" user "Package Geometry/Place Bound Bottom")
		(35 "F.Fab" user "Ref Des/Assembly Top")
		(33 "B.Fab" user "Ref Des/Assembly Bottom")
	)
	(footprint ""
		(layer "F.Cu")
		(at 323.018404 -334.986376 -90)
		(property "Reference" "PC82_C1P0_2"
			(at 0 0 270)
			(layer "F.SilkS")
			(hide yes)
			(effects
				(font
					(size 1.27 1.27)
				)
			)
		)
		(property "Value" ""
			(at 0 0 270)
			(layer "F.Fab")
			(effects
				(font
					(size 1.27 1.27)
				)
			)
		)
		(duplicate_pad_numbers_are_jumpers no)
		(fp_line
			(start -0.7874 0.4064)
			(end -0.7874 -0.4064)
			(stroke
				(width 0.1524)
				(type default)
			)
			(layer "F.SilkS")
		)
		(fp_line
			(start 0.7874 0.4064)
			(end -0.7874 0.4064)
			(stroke
				(width 0.1524)
				(type default)
			)
			(layer "F.SilkS")
		)
		(fp_line
			(start -0.7874 -0.4064)
			(end 0.7874 -0.4064)
			(stroke
				(width 0.1524)
				(type default)
			)
			(layer "F.SilkS")
		)
		(fp_line
			(start 0.7874 -0.4064)
			(end 0.7874 0.4064)
			(stroke
				(width 0.1524)
				(type default)
			)
			(layer "F.SilkS")
		)
		(fp_line
			(start -0.67945 0.3048)
			(end -0.67945 -0.305054)
			(stroke
				(width 0.1)
				(type default)
			)
			(layer "F.Fab")
		)
		(fp_line
			(start -0.12065 0.3048)
			(end -0.67945 0.3048)
			(stroke
				(width 0.1)
				(type default)
			)
			(layer "F.Fab")
		)
		(fp_line
			(start 0.120396 0.3048)
			(end 0.120396 0.2794)
			(stroke
				(width 0.1)
				(type default)
			)
			(layer "F.Fab")
		)
		(fp_line
			(start 0.67945 0.3048)
			(end 0.120396 0.3048)
			(stroke
				(width 0.1)
				(type default)
			)
			(layer "F.Fab")
		)
		(fp_line
			(start -0.12065 0.2794)
			(end -0.12065 0.3048)
			(stroke
				(width 0.1)
				(type default)
			)
			(layer "F.Fab")
		)
		(fp_line
			(start 0.120396 0.2794)
			(end -0.12065 0.2794)
			(stroke
				(width 0.1)
				(type default)
			)
			(layer "F.Fab")
		)
		(fp_line
			(start -0.12065 -0.2794)
			(end 0.12065 -0.2794)
			(stroke
				(width 0.1)
				(type default)
			)
			(layer "F.Fab")
		)
		(fp_line
			(start 0.12065 -0.2794)
			(end 0.12065 -0.3048)
			(stroke
				(width 0.1)
				(type default)
			)
			(layer "F.Fab")
		)
		(fp_line
			(start 0.12065 -0.3048)
			(end 0.67945 -0.3048)
			(stroke
				(width 0.1)
				(type default)
			)
			(layer "F.Fab")
		)
		(fp_line
			(start 0.67945 -0.3048)
			(end 0.67945 0.3048)
			(stroke
				(width 0.1)
				(type default)
			)
			(layer "F.Fab")
		)
		(fp_line
			(start -0.67945 -0.305054)
			(end -0.12065 -0.305054)
			(stroke
				(width 0.1)
				(type default)
			)
			(layer "F.Fab")
		)
		(fp_line
			(start -0.12065 -0.305054)
			(end -0.12065 -0.2794)
			(stroke
				(width 0.1)
				(type default)
			)
			(layer "F.Fab")
		)
		(pad "1" smd circle
			(at -0.40005 0 270)
			(size 0 0)
			(layers "F.Cu" "F.Mask" "F.Paste")
			(net "PVDDCR_CPU1_P0_PVCC")
		)
		(pad "2" smd circle
			(at 0.40005 0 270)
			(size 0 0)
			(layers "F.Cu" "F.Mask" "F.Paste")
			(net "GND")
		)
	)
)
